# BASEBOARD_FAB2 (Tioga Pass) — schematic netlist excerpt (pin names and nets, part order shuffled) for the footprints in the layout excerpt that follows; sources: Cadence DE-HDL packaged netlist, KiCad conversion of Wiwynn_Tioga_Pass_MB.brd

R9A2  RES  33.2 1% EMPTY  pkg 0402  page 111 : A = XDP_PCH_CPU_TCK0 ; B = XDP_CPU_GTL_TCK_R2
R2W1  RES  10.0K 1% CHIP  pkg 0402  page 187 : A = P3V3_STBY ; B = FM_MEZZB_PRSNT1_N
R2L24  RES  2.26K 1.0% EMPTY  pkg 0402  page 235 : A = P3V3_STBY ; B = PU_VR_PVNN_PCH_FAULT1

(kicad_pcb
	(version 20260206)
	(generator "pcbnew")
	(generator_version "10.0")
	(general
		(thickness 1.6)
		(legacy_teardrops no)
	)
	(paper "A4")
	(title_block
		(title "Wiwynn_Tioga_Pass_MB.brd")
		(comment 1 "Tioga Pass / footprints 2730-2732 of 4770")
	)
	(layers
		(0 "F.Cu" signal "TOP")
		(4 "In1.Cu" signal "L2GND")
		(6 "In2.Cu" signal "L3")
		(8 "In3.Cu" signal "L4GND")
		(10 "In4.Cu" signal "L5")
		(12 "In5.Cu" signal "L6GND")
		(14 "In6.Cu" signal "L7VCC")
		(16 "In7.Cu" signal "L8VCC")
		(18 "In8.Cu" signal "L9GND")
		(20 "In9.Cu" signal "L10")
		(22 "In10.Cu" signal "L11GND")
		(24 "In11.Cu" signal "L12")
		(26 "In12.Cu" signal "L13GND")
		(2 "B.Cu" signal "BOTTOM")
		(9 "F.Adhes" user "F.Adhesive")
		(11 "B.Adhes" user "B.Adhesive")
		(13 "F.Paste" user "Package Geometry/Pastemask Top")
		(15 "B.Paste" user "Package Geometry/Pastemask Bottom")
		(5 "F.SilkS" user "Ref Des/Silkscreen Top")
		(7 "B.SilkS" user "Ref Des/Silkscreen Bottom")
		(1 "F.Mask" user "Board Geometry/Soldermask Top")
		(3 "B.Mask" user "Board Geometry/Soldermask Bottom")
		(17 "Dwgs.User" user "User.Drawings")
		(19 "Cmts.User" user "User.Comments")
		(21 "Eco1.User" user "User.Eco1")
		(23 "Eco2.User" user "User.Eco2")
		(25 "Edge.Cuts" user "Board Geometry/Outline")
		(27 "Margin" user)
		(31 "F.CrtYd" user "Package Geometry/Place Bound Top")
		(29 "B.CrtYd" user "Package Geometry/Place Bound Bottom")
		(35 "F.Fab" user "Ref Des/Assembly Top")
		(33 "B.Fab" user "Ref Des/Assembly Bottom")
	)
	(footprint ""
		(layer "B.Cu")
		(at 396.376906 -156.115258 -90)
		(property "Reference" "R2L24"
			(at 0 0 90)
			(layer "B.SilkS")
			(hide yes)
			(effects
				(font
					(size 1.27 1.27)
				)
				(justify mirror)
			)
		)
		(property "Value" ""
			(at 0 0 90)
			(layer "B.Fab")
			(effects
				(font
					(size 1.27 1.27)
				)
				(justify mirror)
			)
		)
		(duplicate_pad_numbers_are_jumpers no)
		(fp_poly
			(pts
				(xy 0.2794 -0.1016) (xy -0.2794 -0.1016) (xy -0.2794 0.9906) (xy 0.2794 0.9906)
			)
			(stroke
				(width 0)
				(type default)
			)
			(fill no)
			(layer "B.CrtYd")
		)
		(fp_line
			(start -0.2794 0.9906)
			(end -0.2794 -0.1016)
			(stroke
				(width 0.1)
				(type default)
			)
			(layer "B.Fab")
		)
		(fp_line
			(start 0.2794 0.9906)
			(end -0.2794 0.9906)
			(stroke
				(width 0.1)
				(type default)
			)
			(layer "B.Fab")
		)
		(fp_line
			(start -0.2794 -0.1016)
			(end 0.2794 -0.1016)
			(stroke
				(width 0.1)
				(type default)
			)
			(layer "B.Fab")
		)
		(fp_line
			(start 0.2794 -0.1016)
			(end 0.2794 0.9906)
			(stroke
				(width 0.1)
				(type default)
			)
			(layer "B.Fab")
		)
		(pad "1" smd rect
			(at 0 0 90)
			(size 0.508 0.508)
			(layers "B.Cu" "B.Mask" "B.Paste")
			(net "P3V3_STBY")
		)
		(pad "2" smd rect
			(at 0 0.889 90)
			(size 0.508 0.508)
			(layers "B.Cu" "B.Mask" "B.Paste")
			(net "PU_VR_PVNN_PCH_FAULT1")
		)
		(zone
			(layer "B.Cu")
			(hatch none 0.5)
			(connect_pads
				(clearance 0)
			)
			(min_thickness 0.25)
			(keepout
				(tracks not_allowed)
				(vias allowed)
				(pads allowed)
				(copperpour not_allowed)
				(footprints allowed)
			)
			(placement
				(enabled no)
				(sheetname "")
			)
			(fill
				(thermal_gap 0.5)
				(thermal_bridge_width 0.5)
				(island_removal_mode 0)
			)
			(polygon
				(pts
					(xy 395.741906 -155.861258) (xy 395.741906 -156.369258) (xy 396.122906 -156.369258) (xy 396.122906 -155.861258)
				)
			)
		)
		(zone
			(layer "B.Cu")
			(hatch none 0.5)
			(connect_pads
				(clearance 0)
			)
			(min_thickness 0.25)
			(keepout
				(tracks allowed)
				(vias not_allowed)
				(pads allowed)
				(copperpour not_allowed)
				(footprints allowed)
			)
			(placement
				(enabled no)
				(sheetname "")
			)
			(fill
				(thermal_gap 0.5)
				(thermal_bridge_width 0.5)
				(island_removal_mode 0)
			)
			(polygon
				(pts
					(xy 396.122906 -155.861258) (xy 396.122906 -156.369258) (xy 395.741906 -156.369258) (xy 395.741906 -155.861258)
				)
			)
		)
	)
	(footprint ""
		(layer "B.Cu")
		(at 439.1025 -48.641 -90)
		(property "Reference" "R2W1"
			(at 0.8382 -0.67818 270)
			(unlocked yes)
			(layer "B.SilkS")
			(effects
				(font
					(size 0.4064 0.254)
					(thickness 0.1524)
				)
				(justify left mirror)
			)
		)
		(property "Value" ""
			(at 0 0 90)
			(layer "B.Fab")
			(effects
				(font
					(size 1.27 1.27)
				)
				(justify mirror)
			)
		)
		(duplicate_pad_numbers_are_jumpers no)
		(fp_poly
			(pts
				(xy 0.2794 -0.1016) (xy -0.2794 -0.1016) (xy -0.2794 0.9906) (xy 0.2794 0.9906)
			)
			(stroke
				(width 0)
				(type default)
			)
			(fill no)
			(layer "B.CrtYd")
		)
		(fp_line
			(start -0.2794 0.9906)
			(end -0.2794 -0.1016)
			(stroke
				(width 0.1)
				(type default)
			)
			(layer "B.Fab")
		)
		(fp_line
			(start 0.2794 0.9906)
			(end -0.2794 0.9906)
			(stroke
				(width 0.1)
				(type default)
			)
			(layer "B.Fab")
		)
		(fp_line
			(start -0.2794 -0.1016)
			(end 0.2794 -0.1016)
			(stroke
				(width 0.1)
				(type default)
			)
			(layer "B.Fab")
		)
		(fp_line
			(start 0.2794 -0.1016)
			(end 0.2794 0.9906)
			(stroke
				(width 0.1)
				(type default)
			)
			(layer "B.Fab")
		)
		(pad "1" smd rect
			(at 0 0 90)
			(size 0.508 0.508)
			(layers "B.Cu" "B.Mask" "B.Paste")
			(net "P3V3_STBY")
		)
		(pad "2" smd rect
			(at 0 0.889 90)
			(size 0.508 0.508)
			(layers "B.Cu" "B.Mask" "B.Paste")
			(net "FM_MEZZB_PRSNT1_N")
		)
		(zone
			(layer "B.Cu")
			(hatch none 0.5)
			(connect_pads
				(clearance 0)
			)
			(min_thickness 0.25)
			(keepout
				(tracks not_allowed)
				(vias allowed)
				(pads allowed)
				(copperpour not_allowed)
				(footprints allowed)
			)
			(placement
				(enabled no)
				(sheetname "")
			)
			(fill
				(thermal_gap 0.5)
				(thermal_bridge_width 0.5)
				(island_removal_mode 0)
			)
			(polygon
				(pts
					(xy 438.4675 -48.387) (xy 438.4675 -48.895) (xy 438.8485 -48.895) (xy 438.8485 -48.387)
				)
			)
		)
		(zone
			(layer "B.Cu")
			(hatch none 0.5)
			(connect_pads
				(clearance 0)
			)
			(min_thickness 0.25)
			(keepout
				(tracks allowed)
				(vias not_allowed)
				(pads allowed)
				(copperpour not_allowed)
				(footprints allowed)
			)
			(placement
				(enabled no)
				(sheetname "")
			)
			(fill
				(thermal_gap 0.5)
				(thermal_bridge_width 0.5)
				(island_removal_mode 0)
			)
			(polygon
				(pts
					(xy 438.8485 -48.387) (xy 438.8485 -48.895) (xy 438.4675 -48.895) (xy 438.4675 -48.387)
				)
			)
		)
	)
	(footprint ""
		(layer "B.Cu")
		(at 453.5678 -153.6446 180)
		(property "Reference" "R9A2"
			(at 0 0 0)
			(layer "B.SilkS")
			(hide yes)
			(effects
				(font
					(size 1.27 1.27)
				)
				(justify mirror)
			)
		)
		(property "Value" ""
			(at 0 0 0)
			(layer "B.Fab")
			(effects
				(font
					(size 1.27 1.27)
				)
				(justify mirror)
			)
		)
		(duplicate_pad_numbers_are_jumpers no)
		(fp_poly
			(pts
				(xy 0.2794 -0.1016) (xy -0.2794 -0.1016) (xy -0.2794 0.9906) (xy 0.2794 0.9906)
			)
			(stroke
				(width 0)
				(type default)
			)
			(fill no)
			(layer "B.CrtYd")
		)
		(fp_line
			(start 0.2794 0.9906)
			(end -0.2794 0.9906)
			(stroke
				(width 0.1)
				(type default)
			)
			(layer "B.Fab")
		)
		(fp_line
			(start 0.2794 -0.1016)
			(end 0.2794 0.9906)
			(stroke
				(width 0.1)
				(type default)
			)
			(layer "B.Fab")
		)
		(fp_line
			(start -0.2794 0.9906)
			(end -0.2794 -0.1016)
			(stroke
				(width 0.1)
				(type default)
			)
			(layer "B.Fab")
		)
		(fp_line
			(start -0.2794 -0.1016)
			(end 0.2794 -0.1016)
			(stroke
				(width 0.1)
				(type default)
			)
			(layer "B.Fab")
		)
		(pad "1" smd rect
			(at 0 0)
			(size 0.508 0.508)
			(layers "B.Cu" "B.Mask" "B.Paste")
			(net "XDP_PCH_CPU_TCK0")
		)
		(pad "2" smd rect
			(at 0 0.889)
			(size 0.508 0.508)
			(layers "B.Cu" "B.Mask" "B.Paste")
			(net "XDP_CPU_GTL_TCK_R2")
		)
		(zone
			(layer "B.Cu")
			(hatch none 0.5)
			(connect_pads
				(clearance 0)
			)
			(min_thickness 0.25)
			(keepout
				(tracks not_allowed)
				(vias allowed)
				(pads allowed)
				(copperpour not_allowed)
				(footprints allowed)
			)
			(placement
				(enabled no)
				(sheetname "")
			)
			(fill
				(thermal_gap 0.5)
				(thermal_bridge_width 0.5)
				(island_removal_mode 0)
			)
			(polygon
				(pts
					(xy 453.3138 -154.2796) (xy 453.8218 -154.2796) (xy 453.8218 -153.8986) (xy 453.3138 -153.8986)
				)
			)
		)
		(zone
			(layer "B.Cu")
			(hatch none 0.5)
			(connect_pads
				(clearance 0)
			)
			(min_thickness 0.25)
			(keepout
				(tracks allowed)
				(vias not_allowed)
				(pads allowed)
				(copperpour not_allowed)
				(footprints allowed)
			)
			(placement
				(enabled no)
				(sheetname "")
			)
			(fill
				(thermal_gap 0.5)
				(thermal_bridge_width 0.5)
				(island_removal_mode 0)
			)
			(polygon
				(pts
					(xy 453.3138 -153.8986) (xy 453.8218 -153.8986) (xy 453.8218 -154.2796) (xy 453.3138 -154.2796)
				)
			)
		)
	)
)
